# T6G (Grand Teton) — schematic netlist excerpt (pin names and nets, part order shuffled) for the footprints in the layout excerpt that follows; sources: Cadence DE-HDL packaged netlist, KiCad conversion of 04192023_DAF0TMB3IC0_F0TG_MB_C_brd_V02_OCP.brd

R2343  Q_RES  10K 1% EMPTY  pkg 0402LF  page 85 : A = P5V_AUX_VCC ; B = PWRGD_P5V_AUX
R6022  Q_RES  2K 5% EMPTY  pkg 0402LF  page 151 : A = P3V3_AUX ; B = SGPIO_SCM_DI_<1>

(kicad_pcb
	(version 20260206)
	(generator "pcbnew")
	(generator_version "10.0")
	(general
		(thickness 1.6)
		(legacy_teardrops no)
	)
	(paper "A4")
	(title_block
		(title "04192023_DAF0TMB3IC0_F0TG_MB_C_brd_V02_OCP.brd")
		(comment 1 "Grand Teton / footprints 1440-1441 of 8354")
	)
	(layers
		(0 "F.Cu" signal "TOP")
		(4 "In1.Cu" signal "GND")
		(6 "In2.Cu" signal "IN1")
		(8 "In3.Cu" signal "GND1")
		(10 "In4.Cu" signal "IN2")
		(12 "In5.Cu" signal "GND2")
		(14 "In6.Cu" signal "IN3")
		(16 "In7.Cu" signal "GND3")
		(18 "In8.Cu" signal "VCC")
		(20 "In9.Cu" signal "VCC1")
		(22 "In10.Cu" signal "GND4")
		(24 "In11.Cu" signal "IN4")
		(26 "In12.Cu" signal "GND5")
		(28 "In13.Cu" signal "IN5")
		(30 "In14.Cu" signal "GND6")
		(32 "In15.Cu" signal "IN6")
		(34 "In16.Cu" signal "GND7")
		(2 "B.Cu" signal "BOTTOM")
		(9 "F.Adhes" user "F.Adhesive")
		(11 "B.Adhes" user "B.Adhesive")
		(13 "F.Paste" user "Package Geometry/Pastemask Top")
		(15 "B.Paste" user "Package Geometry/Pastemask Bottom")
		(5 "F.SilkS" user "Ref Des/Silkscreen Top")
		(7 "B.SilkS" user "Ref Des/Silkscreen Bottom")
		(1 "F.Mask" user "Board Geometry/Soldermask Top")
		(3 "B.Mask" user "Board Geometry/Soldermask Bottom")
		(17 "Dwgs.User" user "User.Drawings")
		(19 "Cmts.User" user "User.Comments")
		(21 "Eco1.User" user "User.Eco1")
		(23 "Eco2.User" user "User.Eco2")
		(25 "Edge.Cuts" user "Board Geometry/Outline")
		(27 "Margin" user)
		(31 "F.CrtYd" user "Package Geometry/Place Bound Top")
		(29 "B.CrtYd" user "Package Geometry/Place Bound Bottom")
		(35 "F.Fab" user "Ref Des/Assembly Top")
		(33 "B.Fab" user "Ref Des/Assembly Bottom")
	)
	(footprint ""
		(layer "F.Cu")
		(at 406.475946 -134.931404 180)
		(property "Reference" "R2343"
			(at 0 0 180)
			(layer "F.SilkS")
			(hide yes)
			(effects
				(font
					(size 1.27 1.27)
				)
			)
		)
		(property "Value" ""
			(at 0 0 180)
			(layer "F.Fab")
			(effects
				(font
					(size 1.27 1.27)
				)
			)
		)
		(duplicate_pad_numbers_are_jumpers no)
		(fp_line
			(start 0.7874 0.4064)
			(end -0.7874 0.4064)
			(stroke
				(width 0.1524)
				(type default)
			)
			(layer "F.SilkS")
		)
		(fp_line
			(start 0.7874 -0.4064)
			(end 0.7874 0.4064)
			(stroke
				(width 0.1524)
				(type default)
			)
			(layer "F.SilkS")
		)
		(fp_line
			(start -0.7874 0.4064)
			(end -0.7874 -0.4064)
			(stroke
				(width 0.1524)
				(type default)
			)
			(layer "F.SilkS")
		)
		(fp_line
			(start -0.7874 -0.4064)
			(end 0.7874 -0.4064)
			(stroke
				(width 0.1524)
				(type default)
			)
			(layer "F.SilkS")
		)
		(fp_line
			(start 0.67945 0.3048)
			(end 0.120396 0.3048)
			(stroke
				(width 0.1)
				(type default)
			)
			(layer "F.Fab")
		)
		(fp_line
			(start 0.67945 -0.3048)
			(end 0.67945 0.3048)
			(stroke
				(width 0.1)
				(type default)
			)
			(layer "F.Fab")
		)
		(fp_line
			(start 0.12065 -0.2794)
			(end 0.12065 -0.3048)
			(stroke
				(width 0.1)
				(type default)
			)
			(layer "F.Fab")
		)
		(fp_line
			(start 0.12065 -0.3048)
			(end 0.67945 -0.3048)
			(stroke
				(width 0.1)
				(type default)
			)
			(layer "F.Fab")
		)
		(fp_line
			(start 0.120396 0.3048)
			(end 0.120396 0.2794)
			(stroke
				(width 0.1)
				(type default)
			)
			(layer "F.Fab")
		)
		(fp_line
			(start 0.120396 0.2794)
			(end -0.12065 0.2794)
			(stroke
				(width 0.1)
				(type default)
			)
			(layer "F.Fab")
		)
		(fp_line
			(start -0.12065 0.3048)
			(end -0.67945 0.3048)
			(stroke
				(width 0.1)
				(type default)
			)
			(layer "F.Fab")
		)
		(fp_line
			(start -0.12065 0.2794)
			(end -0.12065 0.3048)
			(stroke
				(width 0.1)
				(type default)
			)
			(layer "F.Fab")
		)
		(fp_line
			(start -0.12065 -0.2794)
			(end 0.12065 -0.2794)
			(stroke
				(width 0.1)
				(type default)
			)
			(layer "F.Fab")
		)
		(fp_line
			(start -0.12065 -0.305054)
			(end -0.12065 -0.2794)
			(stroke
				(width 0.1)
				(type default)
			)
			(layer "F.Fab")
		)
		(fp_line
			(start -0.67945 0.3048)
			(end -0.67945 -0.305054)
			(stroke
				(width 0.1)
				(type default)
			)
			(layer "F.Fab")
		)
		(fp_line
			(start -0.67945 -0.305054)
			(end -0.12065 -0.305054)
			(stroke
				(width 0.1)
				(type default)
			)
			(layer "F.Fab")
		)
		(pad "1" smd circle
			(at -0.40005 0 180)
			(size 0 0)
			(layers "F.Cu" "F.Mask" "F.Paste")
			(net "P5V_AUX_VCC")
		)
		(pad "2" smd circle
			(at 0.40005 0 180)
			(size 0 0)
			(layers "F.Cu" "F.Mask" "F.Paste")
			(net "PWRGD_P5V_AUX")
		)
	)
	(footprint ""
		(layer "F.Cu")
		(at 152.991312 -26.68778 -90)
		(property "Reference" "R6022"
			(at 0 0 270)
			(layer "F.SilkS")
			(hide yes)
			(effects
				(font
					(size 1.27 1.27)
				)
			)
		)
		(property "Value" ""
			(at 0 0 270)
			(layer "F.Fab")
			(effects
				(font
					(size 1.27 1.27)
				)
			)
		)
		(duplicate_pad_numbers_are_jumpers no)
		(fp_line
			(start -0.7874 0.4064)
			(end -0.7874 -0.4064)
			(stroke
				(width 0.1524)
				(type default)
			)
			(layer "F.SilkS")
		)
		(fp_line
			(start 0.7874 0.4064)
			(end -0.7874 0.4064)
			(stroke
				(width 0.1524)
				(type default)
			)
			(layer "F.SilkS")
		)
		(fp_line
			(start -0.7874 -0.4064)
			(end 0.7874 -0.4064)
			(stroke
				(width 0.1524)
				(type default)
			)
			(layer "F.SilkS")
		)
		(fp_line
			(start 0.7874 -0.4064)
			(end 0.7874 0.4064)
			(stroke
				(width 0.1524)
				(type default)
			)
			(layer "F.SilkS")
		)
		(fp_line
			(start -0.67945 0.3048)
			(end -0.67945 -0.305054)
			(stroke
				(width 0.1)
				(type default)
			)
			(layer "F.Fab")
		)
		(fp_line
			(start -0.12065 0.3048)
			(end -0.67945 0.3048)
			(stroke
				(width 0.1)
				(type default)
			)
			(layer "F.Fab")
		)
		(fp_line
			(start 0.120396 0.3048)
			(end 0.120396 0.2794)
			(stroke
				(width 0.1)
				(type default)
			)
			(layer "F.Fab")
		)
		(fp_line
			(start 0.67945 0.3048)
			(end 0.120396 0.3048)
			(stroke
				(width 0.1)
				(type default)
			)
			(layer "F.Fab")
		)
		(fp_line
			(start -0.12065 0.2794)
			(end -0.12065 0.3048)
			(stroke
				(width 0.1)
				(type default)
			)
			(layer "F.Fab")
		)
		(fp_line
			(start 0.120396 0.2794)
			(end -0.12065 0.2794)
			(stroke
				(width 0.1)
				(type default)
			)
			(layer "F.Fab")
		)
		(fp_line
			(start -0.12065 -0.2794)
			(end 0.12065 -0.2794)
			(stroke
				(width 0.1)
				(type default)
			)
			(layer "F.Fab")
		)
		(fp_line
			(start 0.12065 -0.2794)
			(end 0.12065 -0.3048)
			(stroke
				(width 0.1)
				(type default)
			)
			(layer "F.Fab")
		)
		(fp_line
			(start 0.12065 -0.3048)
			(end 0.67945 -0.3048)
			(stroke
				(width 0.1)
				(type default)
			)
			(layer "F.Fab")
		)
		(fp_line
			(start 0.67945 -0.3048)
			(end 0.67945 0.3048)
			(stroke
				(width 0.1)
				(type default)
			)
			(layer "F.Fab")
		)
		(fp_line
			(start -0.67945 -0.305054)
			(end -0.12065 -0.305054)
			(stroke
				(width 0.1)
				(type default)
			)
			(layer "F.Fab")
		)
		(fp_line
			(start -0.12065 -0.305054)
			(end -0.12065 -0.2794)
			(stroke
				(width 0.1)
				(type default)
			)
			(layer "F.Fab")
		)
		(pad "1" smd circle
			(at -0.40005 0 270)
			(size 0 0)
			(layers "F.Cu" "F.Mask" "F.Paste")
			(net "P3V3_AUX")
		)
		(pad "2" smd circle
			(at 0.40005 0 270)
			(size 0 0)
			(layers "F.Cu" "F.Mask" "F.Paste")
			(net "SGPIO_SCM_DI_<1>")
		)
	)
)
